(kicad_pcb
	(version 20240108)
	(generator "pcbnew")
	(generator_version "8.0")
	(general
		(thickness 1.62)
		(legacy_teardrops no)
	)
	(paper "A4")
	(title_block
		(title "Jetson Orin Baseboard")
		(date "2025-03-12")
		(rev "1.3.4")
		(company "Antmicro Ltd")
		(comment 1 "www.antmicro.com")
		(comment 9 "footprints 80-84 of 677")
	)
	(layers
		(0 "F.Cu" signal)
		(1 "In1.Cu" signal)
		(2 "In2.Cu" signal)
		(3 "In3.Cu" signal)
		(4 "In4.Cu" jumper)
		(5 "In5.Cu" signal)
		(6 "In6.Cu" signal)
		(31 "B.Cu" signal)
		(32 "B.Adhes" user "B.Adhesive")
		(33 "F.Adhes" user "F.Adhesive")
		(34 "B.Paste" user)
		(35 "F.Paste" user)
		(36 "B.SilkS" user "B.Silkscreen")
		(37 "F.SilkS" user "F.Silkscreen")
		(38 "B.Mask" user)
		(39 "F.Mask" user)
		(40 "Dwgs.User" user "User.Drawings")
		(41 "Cmts.User" user "User.Comments")
		(42 "Eco1.User" user "User.Eco1")
		(43 "Eco2.User" user "User.Eco2")
		(44 "Edge.Cuts" user)
		(45 "Margin" user)
		(46 "B.CrtYd" user "B.Courtyard")
		(47 "F.CrtYd" user "F.Courtyard")
		(48 "B.Fab" user)
		(49 "F.Fab" user)
	)
	(footprint "antmicro-footprints:R_0402_1005Metric"
		(layer "F.Cu")
		(at 89.95 88.7 -90)
		(descr "Resistor SMD 0402")
		(tags "resistor SMD 0402")
		(property "Reference" "R277"
			(at -0.88 -0.53 -90)
			(layer "F.SilkS")
			(effects
				(font
					(size 0.7 0.7)
					(thickness 0.15)
				)
				(justify left bottom)
			)
		)
		(property "Value" "R_0R_0402"
			(at 0 1.4 -90)
			(layer "F.Fab")
			(effects
				(font
					(size 0.7 0.7)
					(thickness 0.15)
				)
				(justify left bottom)
			)
		)
		(property "Footprint" "antmicro-footprints:R_0402_1005Metric"
			(at 0 0 -90)
			(layer "F.Fab")
			(hide yes)
			(effects
				(font
					(size 1.27 1.27)
					(thickness 0.15)
				)
			)
		)
		(property "Datasheet" "https://industrial.panasonic.com/cdbs/www-data/pdf/RDA0000/AOA0000C301.pdf"
			(at 0 0 -90)
			(layer "F.Fab")
			(hide yes)
			(effects
				(font
					(size 1.27 1.27)
					(thickness 0.15)
				)
			)
		)
		(property "Author" "Antmicro"
			(at 1.25 178.65 0)
			(layer "F.Fab")
			(hide yes)
			(effects
				(font
					(size 1 1)
					(thickness 0.15)
				)
			)
		)
		(property "Current" "1A"
			(at 1.25 178.65 0)
			(layer "F.Fab")
			(hide yes)
			(effects
				(font
					(size 1 1)
					(thickness 0.15)
				)
			)
		)
		(property "License" "Apache-2.0"
			(at 1.25 178.65 0)
			(layer "F.Fab")
			(hide yes)
			(effects
				(font
					(size 1 1)
					(thickness 0.15)
				)
			)
		)
		(property "MPN" "ERJ2GE0R00X"
			(at 1.25 178.65 0)
			(layer "F.Fab")
			(hide yes)
			(effects
				(font
					(size 1 1)
					(thickness 0.15)
				)
			)
		)
		(property "Manufacturer" "Panasonic"
			(at 1.25 178.65 0)
			(layer "F.Fab")
			(hide yes)
			(effects
				(font
					(size 1 1)
					(thickness 0.15)
				)
			)
		)
		(property "Tolerance" ""
			(at 1.25 178.65 0)
			(layer "F.Fab")
			(hide yes)
			(effects
				(font
					(size 1 1)
					(thickness 0.15)
				)
			)
		)
		(property "Val" "0R"
			(at 1.25 178.65 0)
			(layer "F.Fab")
			(hide yes)
			(effects
				(font
					(size 1 1)
					(thickness 0.15)
				)
			)
		)
		(sheetname "HDMI")
		(sheetfile "hdmi.kicad_sch")
		(attr smd)
		(fp_rect
			(start -0.925 -0.47)
			(end 0.925 0.47)
			(stroke
				(width 0.05)
				(type default)
			)
			(fill none)
			(layer "F.CrtYd")
		)
		(fp_rect
			(start -0.5 -0.25)
			(end 0.5 0.25)
			(stroke
				(width 0.15)
				(type solid)
			)
			(fill none)
			(layer "F.Fab")
		)
		(fp_text user "${REFERENCE}"
			(at -0.95 3.168 -90)
			(layer "F.Fab")
			(hide yes)
			(effects
				(font
					(size 0.7 0.7)
					(thickness 0.15)
				)
				(justify left bottom)
			)
		)
		(fp_text user "License: Apache-2.0"
			(at -0.95 5.169 -90)
			(layer "F.Fab")
			(hide yes)
			(effects
				(font
					(size 0.7 0.7)
					(thickness 0.15)
				)
				(justify left bottom)
			)
		)
		(fp_text user "Author: Antmicro"
			(at -0.95 4.169 -90)
			(layer "F.Fab")
			(hide yes)
			(effects
				(font
					(size 0.7 0.7)
					(thickness 0.15)
				)
				(justify left bottom)
			)
		)
		(pad "1" smd roundrect
			(at -0.48 0 270)
			(size 0.59 0.64)
			(layers "F.Cu" "F.Paste" "F.Mask")
			(roundrect_rratio 0.25)
			(net 679 "/HDMI/DP_MUX_AUX_A+")
			(pintype "passive")
		)
		(pad "2" smd roundrect
			(at 0.48 0 270)
			(size 0.59 0.64)
			(layers "F.Cu" "F.Paste" "F.Mask")
			(roundrect_rratio 0.25)
			(net 555 "/HDMI/HDMI_SCL_3V3")
			(pintype "passive")
		)
	)
	(footprint "antmicro-footprints:R_0402_1005Metric"
		(layer "F.Cu")
		(at 68.74 82.31 -90)
		(descr "Resistor SMD 0402")
		(tags "resistor SMD 0402")
		(property "Reference" "R2"
			(at 0.84 0.37 90)
			(layer "F.SilkS")
			(effects
				(font
					(size 0.7 0.7)
					(thickness 0.15)
				)
				(justify right top)
			)
		)
		(property "Value" "R_0R_0402"
			(at 0 1.4 90)
			(layer "F.Fab")
			(effects
				(font
					(size 0.7 0.7)
					(thickness 0.15)
				)
				(justify right top)
			)
		)
		(property "Footprint" "antmicro-footprints:R_0402_1005Metric"
			(at 0 0 90)
			(layer "F.Fab")
			(hide yes)
			(effects
				(font
					(size 1.27 1.27)
					(thickness 0.15)
				)
			)
		)
		(property "Datasheet" "https://industrial.panasonic.com/cdbs/www-data/pdf/RDA0000/AOA0000C301.pdf"
			(at 0 0 90)
			(layer "F.Fab")
			(hide yes)
			(effects
				(font
					(size 1.27 1.27)
					(thickness 0.15)
				)
			)
		)
		(property "Author" "Antmicro"
			(at -14.1 151 0)
			(layer "F.Fab")
			(hide yes)
			(effects
				(font
					(size 1 1)
					(thickness 0.15)
				)
			)
		)
		(property "Current" "1A"
			(at -14.1 151 0)
			(layer "F.Fab")
			(hide yes)
			(effects
				(font
					(size 1 1)
					(thickness 0.15)
				)
			)
		)
		(property "License" "Apache-2.0"
			(at -14.1 151 0)
			(layer "F.Fab")
			(hide yes)
			(effects
				(font
					(size 1 1)
					(thickness 0.15)
				)
			)
		)
		(property "MPN" "ERJ2GE0R00X"
			(at -14.1 151 0)
			(layer "F.Fab")
			(hide yes)
			(effects
				(font
					(size 1 1)
					(thickness 0.15)
				)
			)
		)
		(property "Manufacturer" "Panasonic"
			(at -14.1 151 0)
			(layer "F.Fab")
			(hide yes)
			(effects
				(font
					(size 1 1)
					(thickness 0.15)
				)
			)
		)
		(property "Tolerance" ""
			(at -14.1 151 0)
			(layer "F.Fab")
			(hide yes)
			(effects
				(font
					(size 1 1)
					(thickness 0.15)
				)
			)
		)
		(property "Val" "0R"
			(at -14.1 151 0)
			(layer "F.Fab")
			(hide yes)
			(effects
				(font
					(size 1 1)
					(thickness 0.15)
				)
			)
		)
		(sheetname "SoM")
		(sheetfile "som.kicad_sch")
		(attr smd)
		(fp_rect
			(start -0.925 -0.47)
			(end 0.925 0.47)
			(stroke
				(width 0.05)
				(type default)
			)
			(fill none)
			(layer "F.CrtYd")
		)
		(fp_rect
			(start -0.5 -0.25)
			(end 0.5 0.25)
			(stroke
				(width 0.15)
				(type solid)
			)
			(fill none)
			(layer "F.Fab")
		)
		(fp_text user "License: Apache-2.0"
			(at -0.95 5.169 90)
			(layer "F.Fab")
			(hide yes)
			(effects
				(font
					(size 0.7 0.7)
					(thickness 0.15)
				)
				(justify right top)
			)
		)
		(fp_text user "${REFERENCE}"
			(at -0.95 3.168 90)
			(layer "F.Fab")
			(hide yes)
			(effects
				(font
					(size 0.7 0.7)
					(thickness 0.15)
				)
				(justify right top)
			)
		)
		(fp_text user "Author: Antmicro"
			(at -0.95 4.169 90)
			(layer "F.Fab")
			(hide yes)
			(effects
				(font
					(size 0.7 0.7)
					(thickness 0.15)
				)
				(justify right top)
			)
		)
		(pad "1" smd roundrect
			(at -0.48 0 270)
			(size 0.59 0.64)
			(layers "F.Cu" "F.Paste" "F.Mask")
			(roundrect_rratio 0.25)
			(net 752 "Net-(J15H-GPIO12{slash}PWM)")
			(pintype "passive")
		)
		(pad "2" smd roundrect
			(at 0.48 0 270)
			(size 0.59 0.64)
			(layers "F.Cu" "F.Paste" "F.Mask")
			(roundrect_rratio 0.25)
			(net 83 "GPIO12")
			(pintype "passive")
		)
	)
	(footprint "antmicro-footprints:R_0402_1005Metric"
		(layer "F.Cu")
		(at 127.05 99.55 180)
		(descr "Resistor SMD 0402")
		(tags "resistor SMD 0402")
		(property "Reference" "R14"
			(at 1 -1.35 0)
			(layer "F.SilkS")
			(effects
				(font
					(size 0.7 0.7)
					(thickness 0.15)
				)
				(justify left bottom)
			)
		)
		(property "Value" "R_0R_0402"
			(at 0 1.4 180)
			(layer "F.Fab")
			(effects
				(font
					(size 0.7 0.7)
					(thickness 0.15)
				)
				(justify left bottom)
			)
		)
		(property "Footprint" "antmicro-footprints:R_0402_1005Metric"
			(at 0 0 180)
			(layer "F.Fab")
			(hide yes)
			(effects
				(font
					(size 1.27 1.27)
					(thickness 0.15)
				)
			)
		)
		(property "Datasheet" "https://industrial.panasonic.com/cdbs/www-data/pdf/RDA0000/AOA0000C301.pdf"
			(at 0 0 180)
			(layer "F.Fab")
			(hide yes)
			(effects
				(font
					(size 1.27 1.27)
					(thickness 0.15)
				)
			)
		)
		(property "Author" "Antmicro"
			(at 254.1 199.1 0)
			(layer "F.Fab")
			(hide yes)
			(effects
				(font
					(size 1 1)
					(thickness 0.15)
				)
			)
		)
		(property "Current" "1A"
			(at 254.1 199.1 0)
			(layer "F.Fab")
			(hide yes)
			(effects
				(font
					(size 1 1)
					(thickness 0.15)
				)
			)
		)
		(property "License" "Apache-2.0"
			(at 254.1 199.1 0)
			(layer "F.Fab")
			(hide yes)
			(effects
				(font
					(size 1 1)
					(thickness 0.15)
				)
			)
		)
		(property "MPN" "ERJ2GE0R00X"
			(at 254.1 199.1 0)
			(layer "F.Fab")
			(hide yes)
			(effects
				(font
					(size 1 1)
					(thickness 0.15)
				)
			)
		)
		(property "Manufacturer" "Panasonic"
			(at 254.1 199.1 0)
			(layer "F.Fab")
			(hide yes)
			(effects
				(font
					(size 1 1)
					(thickness 0.15)
				)
			)
		)
		(property "Tolerance" ""
			(at 254.1 199.1 0)
			(layer "F.Fab")
			(hide yes)
			(effects
				(font
					(size 1 1)
					(thickness 0.15)
				)
			)
		)
		(property "Val" "0R"
			(at 254.1 199.1 0)
			(layer "F.Fab")
			(hide yes)
			(effects
				(font
					(size 1 1)
					(thickness 0.15)
				)
			)
		)
		(sheetname "M.2")
		(sheetfile "m-2.kicad_sch")
		(attr smd)
		(fp_rect
			(start -0.925 -0.47)
			(end 0.925 0.47)
			(stroke
				(width 0.05)
				(type default)
			)
			(fill none)
			(layer "F.CrtYd")
		)
		(fp_rect
			(start -0.5 -0.25)
			(end 0.5 0.25)
			(stroke
				(width 0.15)
				(type solid)
			)
			(fill none)
			(layer "F.Fab")
		)
		(fp_text user "Author: Antmicro"
			(at -0.95 4.169 180)
			(layer "F.Fab")
			(hide yes)
			(effects
				(font
					(size 0.7 0.7)
					(thickness 0.15)
				)
				(justify left bottom)
			)
		)
		(fp_text user "${REFERENCE}"
			(at -0.95 3.168 180)
			(layer "F.Fab")
			(hide yes)
			(effects
				(font
					(size 0.7 0.7)
					(thickness 0.15)
				)
				(justify left bottom)
			)
		)
		(fp_text user "License: Apache-2.0"
			(at -0.95 5.169 180)
			(layer "F.Fab")
			(hide yes)
			(effects
				(font
					(size 0.7 0.7)
					(thickness 0.15)
				)
				(justify left bottom)
			)
		)
		(pad "1" smd roundrect
			(at -0.48 0 180)
			(size 0.59 0.64)
			(layers "F.Cu" "F.Paste" "F.Mask")
			(roundrect_rratio 0.25)
			(net 453 "PCIE_WAKE*")
			(pintype "passive")
		)
		(pad "2" smd roundrect
			(at 0.48 0 180)
			(size 0.59 0.64)
			(layers "F.Cu" "F.Paste" "F.Mask")
			(roundrect_rratio 0.25)
			(net 171 "/M.2/PCIE_WAKE_SEL1")
			(pintype "passive")
		)
	)
	(footprint "antmicro-footprints:R_0402_1005Metric"
		(layer "F.Cu")
		(at 129.3 92.2 180)
		(descr "Resistor SMD 0402")
		(tags "resistor SMD 0402")
		(property "Reference" "R52"
			(at 2.925 -0.45 180)
			(layer "F.SilkS")
			(effects
				(font
					(size 0.7 0.7)
					(thickness 0.15)
				)
				(justify left bottom)
			)
		)
		(property "Value" "R_0R_0402"
			(at 0 1.4 180)
			(layer "F.Fab")
			(effects
				(font
					(size 0.7 0.7)
					(thickness 0.15)
				)
				(justify left bottom)
			)
		)
		(property "Footprint" "antmicro-footprints:R_0402_1005Metric"
			(at 0 0 180)
			(layer "F.Fab")
			(hide yes)
			(effects
				(font
					(size 1.27 1.27)
					(thickness 0.15)
				)
			)
		)
		(property "Datasheet" "https://industrial.panasonic.com/cdbs/www-data/pdf/RDA0000/AOA0000C301.pdf"
			(at 0 0 180)
			(layer "F.Fab")
			(hide yes)
			(effects
				(font
					(size 1.27 1.27)
					(thickness 0.15)
				)
			)
		)
		(property "Author" "Antmicro"
			(at 258.6 184.4 0)
			(layer "F.Fab")
			(hide yes)
			(effects
				(font
					(size 1 1)
					(thickness 0.15)
				)
			)
		)
		(property "Current" "1A"
			(at 258.6 184.4 0)
			(layer "F.Fab")
			(hide yes)
			(effects
				(font
					(size 1 1)
					(thickness 0.15)
				)
			)
		)
		(property "License" "Apache-2.0"
			(at 258.6 184.4 0)
			(layer "F.Fab")
			(hide yes)
			(effects
				(font
					(size 1 1)
					(thickness 0.15)
				)
			)
		)
		(property "MPN" "ERJ2GE0R00X"
			(at 258.6 184.4 0)
			(layer "F.Fab")
			(hide yes)
			(effects
				(font
					(size 1 1)
					(thickness 0.15)
				)
			)
		)
		(property "Manufacturer" "Panasonic"
			(at 258.6 184.4 0)
			(layer "F.Fab")
			(hide yes)
			(effects
				(font
					(size 1 1)
					(thickness 0.15)
				)
			)
		)
		(property "Tolerance" ""
			(at 258.6 184.4 0)
			(layer "F.Fab")
			(hide yes)
			(effects
				(font
					(size 1 1)
					(thickness 0.15)
				)
			)
		)
		(property "Val" "0R"
			(at 258.6 184.4 0)
			(layer "F.Fab")
			(hide yes)
			(effects
				(font
					(size 1 1)
					(thickness 0.15)
				)
			)
		)
		(sheetname "M.2")
		(sheetfile "m-2.kicad_sch")
		(attr smd)
		(fp_rect
			(start -0.925 -0.47)
			(end 0.925 0.47)
			(stroke
				(width 0.05)
				(type default)
			)
			(fill none)
			(layer "F.CrtYd")
		)
		(fp_rect
			(start -0.5 -0.25)
			(end 0.5 0.25)
			(stroke
				(width 0.15)
				(type solid)
			)
			(fill none)
			(layer "F.Fab")
		)
		(fp_text user "Author: Antmicro"
			(at -0.95 4.169 180)
			(layer "F.Fab")
			(hide yes)
			(effects
				(font
					(size 0.7 0.7)
					(thickness 0.15)
				)
				(justify left bottom)
			)
		)
		(fp_text user "${REFERENCE}"
			(at -0.95 3.168 180)
			(layer "F.Fab")
			(hide yes)
			(effects
				(font
					(size 0.7 0.7)
					(thickness 0.15)
				)
				(justify left bottom)
			)
		)
		(fp_text user "License: Apache-2.0"
			(at -0.95 5.169 180)
			(layer "F.Fab")
			(hide yes)
			(effects
				(font
					(size 0.7 0.7)
					(thickness 0.15)
				)
				(justify left bottom)
			)
		)
		(pad "1" smd roundrect
			(at -0.48 0 180)
			(size 0.59 0.64)
			(layers "F.Cu" "F.Paste" "F.Mask")
			(roundrect_rratio 0.25)
			(net 434 "USB1_D_N")
			(pintype "passive")
		)
		(pad "2" smd roundrect
			(at 0.48 0 180)
			(size 0.59 0.64)
			(layers "F.Cu" "F.Paste" "F.Mask")
			(roundrect_rratio 0.25)
			(net 617 "/M.2/USB_E_N")
			(pintype "passive")
		)
	)
	(footprint "antmicro-footprints:R_0402_1005Metric"
		(layer "F.Cu")
		(at 148 108.5)
		(descr "Resistor SMD 0402")
		(tags "resistor SMD 0402")
		(property "Reference" "R120"
			(at -1.21 6.1 0)
			(layer "F.SilkS")
			(effects
				(font
					(size 0.7 0.7)
					(thickness 0.15)
				)
				(justify left bottom)
			)
		)
		(property "Value" "R_0R_0402"
			(at 0 1.4 0)
			(layer "F.Fab")
			(effects
				(font
					(size 0.7 0.7)
					(thickness 0.15)
				)
				(justify left bottom)
			)
		)
		(property "Footprint" "antmicro-footprints:R_0402_1005Metric"
			(at 0 0 0)
			(layer "F.Fab")
			(hide yes)
			(effects
				(font
					(size 1.27 1.27)
					(thickness 0.15)
				)
			)
		)
		(property "Datasheet" "https://industrial.panasonic.com/cdbs/www-data/pdf/RDA0000/AOA0000C301.pdf"
			(at 0 0 0)
			(layer "F.Fab")
			(hide yes)
			(effects
				(font
					(size 1.27 1.27)
					(thickness 0.15)
				)
			)
		)
		(property "Author" "Antmicro"
			(at 0 0 0)
			(layer "F.Fab")
			(hide yes)
			(effects
				(font
					(size 1 1)
					(thickness 0.15)
				)
			)
		)
		(property "Current" "1A"
			(at 0 0 0)
			(layer "F.Fab")
			(hide yes)
			(effects
				(font
					(size 1 1)
					(thickness 0.15)
				)
			)
		)
		(property "License" "Apache-2.0"
			(at 0 0 0)
			(layer "F.Fab")
			(hide yes)
			(effects
				(font
					(size 1 1)
					(thickness 0.15)
				)
			)
		)
		(property "MPN" "ERJ2GE0R00X"
			(at 0 0 0)
			(layer "F.Fab")
			(hide yes)
			(effects
				(font
					(size 1 1)
					(thickness 0.15)
				)
			)
		)
		(property "Manufacturer" "Panasonic"
			(at 0 0 0)
			(layer "F.Fab")
			(hide yes)
			(effects
				(font
					(size 1 1)
					(thickness 0.15)
				)
			)
		)
		(property "Tolerance" ""
			(at 0 0 0)
			(layer "F.Fab")
			(hide yes)
			(effects
				(font
					(size 1 1)
					(thickness 0.15)
				)
			)
		)
		(property "Val" "0R"
			(at 0 0 0)
			(layer "F.Fab")
			(hide yes)
			(effects
				(font
					(size 1 1)
					(thickness 0.15)
				)
			)
		)
		(sheetname "Peripherals")
		(sheetfile "peripherals.kicad_sch")
		(attr smd exclude_from_pos_files exclude_from_bom dnp)
		(fp_rect
			(start -0.925 -0.47)
			(end 0.925 0.47)
			(stroke
				(width 0.05)
				(type default)
			)
			(fill none)
			(layer "F.CrtYd")
		)
		(fp_rect
			(start -0.5 -0.25)
			(end 0.5 0.25)
			(stroke
				(width 0.15)
				(type solid)
			)
			(fill none)
			(layer "F.Fab")
		)
		(fp_text user "Author: Antmicro"
			(at -0.95 4.169 0)
			(layer "F.Fab")
			(hide yes)
			(effects
				(font
					(size 0.7 0.7)
					(thickness 0.15)
				)
				(justify left bottom)
			)
		)
		(fp_text user "License: Apache-2.0"
			(at -0.95 5.169 0)
			(layer "F.Fab")
			(hide yes)
			(effects
				(font
					(size 0.7 0.7)
					(thickness 0.15)
				)
				(justify left bottom)
			)
		)
		(fp_text user "${REFERENCE}"
			(at -0.95 3.168 0)
			(layer "F.Fab")
			(hide yes)
			(effects
				(font
					(size 0.7 0.7)
					(thickness 0.15)
				)
				(justify left bottom)
			)
		)
		(pad "1" smd roundrect
			(at -0.48 0)
			(size 0.59 0.64)
			(layers "F.Cu" "F.Paste" "F.Mask")
			(roundrect_rratio 0.25)
			(net 597 "Net-(J11-Pad64)")
			(pintype "passive")
		)
		(pad "2" smd roundrect
			(at 0.48 0)
			(size 0.59 0.64)
			(layers "F.Cu" "F.Paste" "F.Mask")
			(roundrect_rratio 0.25)
			(net 130 "I2C2_SDA")
			(pintype "passive")
		)
	)
)
